#ISCELL
  mstr_misc dns *
  *
#ISCELL
  mstr_symbols intel_corp_bpage *
  *
#CELL
  mstr_discrete res *
  page89_i1
#ISCELL
  mstr_standard offpage *
  page89_i10
#ISCELL
  mstr_standard offpage *
  page89_i11
#ISCELL
  mstr_standard offpage *
  page89_i12
#ISCELL
  mstr_standard offpage *
  page89_i13
#ISCELL
  mstr_standard offpage *
  page89_i14
#ISCELL
  mstr_symbols gnd *
  page89_i16
#ISCELL
  mstr_symbols pvpp_abc *
  page89_i17
#CELL
  mstr_discrete res *
  page89_i2
#ISCELL
  mstr_standard offpage *
  page89_i22
#CELL
  mstr_discrete res *
  page89_i23
#CELL
  mstr_discrete res *
  page89_i26
#CELL
  mstr_discrete res *
  page89_i27
#ISCELL
  mstr_symbols p3v3_stby *
  page89_i28
#ISCELL
  mstr_symbols p3v3_stby *
  page89_i29
#CELL
  mstr_discrete res *
  page89_i3
#ISCELL
  mstr_symbols gnd *
  page89_i30
#ISCELL
  mstr_symbols gnd *
  page89_i31
#ISCELL
  mstr_standard offpage *
  page89_i33
#CELL
  mstr_discrete res *
  page89_i34
#CELL
  mstr_discrete npn_dual *
  page89_i35
#ISCELL
  mstr_symbols gnd *
  page89_i39
#CELL
  mstr_discrete res *
  page89_i4
#CELL
  mstr_discrete res *
  page89_i40
#ISCELL
  mstr_symbols pvpp_abc *
  page89_i41
#CELL
  mstr_discrete res *
  page89_i45
#CELL
  mstr_discrete npn_dual *
  page89_i46
#ISCELL
  mstr_symbols gnd *
  page89_i47
#ISCELL
  mstr_symbols gnd *
  page89_i48
#CELL
  mstr_discrete res *
  page89_i49
#CELL
  mstr_discrete res *
  page89_i5
#ISCELL
  mstr_symbols p3v3_stby *
  page89_i50
#CELL
  mstr_discrete npn_dual *
  page89_i51
#CELL
  mstr_discrete npn_dual *
  page89_i52
#CELL
  mstr_discrete npn *
  page89_i53
#CELL
  mstr_discrete res *
  page89_i54
#CELL
  mstr_discrete npn *
  page89_i55
#CELL
  mstr_discrete res *
  page89_i56
#CELL
  mstr_discrete res *
  page89_i6
#CELL
  mstr_discrete res *
  page89_i7
#ISCELL
  mstr_standard offpage *
  page89_i9
